(kicad_pcb
	(version 20260206)
	(generator "pcbnew")
	(generator_version "10.0")
	(general
		(thickness 1.6)
		(legacy_teardrops no)
	)
	(paper "A4")
	(title_block
		(title "03242023_DA0F0TMBIJ0_F0T_Motherboard_J_brd_V01_OCP.brd")
		(comment 1 "Grand Teton / footprint 3133 of 6105 (J32), pads 225-291 of 291")
	)
	(layers
		(0 "F.Cu" signal "TOP")
		(4 "In1.Cu" signal "GND")
		(6 "In2.Cu" signal "IN1")
		(8 "In3.Cu" signal "GND1")
		(10 "In4.Cu" signal "IN2")
		(12 "In5.Cu" signal "GND2")
		(14 "In6.Cu" signal "IN3")
		(16 "In7.Cu" signal "GND3")
		(18 "In8.Cu" signal "VCC")
		(20 "In9.Cu" signal "VCC1")
		(22 "In10.Cu" signal "GND4")
		(24 "In11.Cu" signal "IN4")
		(26 "In12.Cu" signal "GND5")
		(28 "In13.Cu" signal "IN5")
		(30 "In14.Cu" signal "GND6")
		(32 "In15.Cu" signal "IN6")
		(34 "In16.Cu" signal "GND7")
		(2 "B.Cu" signal "BOTTOM")
		(9 "F.Adhes" user "F.Adhesive")
		(11 "B.Adhes" user "B.Adhesive")
		(13 "F.Paste" user "Package Geometry/Pastemask Top")
		(15 "B.Paste" user "Package Geometry/Pastemask Bottom")
		(5 "F.SilkS" user "Ref Des/Silkscreen Top")
		(7 "B.SilkS" user "Ref Des/Silkscreen Bottom")
		(1 "F.Mask" user "Board Geometry/Soldermask Top")
		(3 "B.Mask" user "Board Geometry/Soldermask Bottom")
		(17 "Dwgs.User" user "User.Drawings")
		(19 "Cmts.User" user "User.Comments")
		(21 "Eco1.User" user "User.Eco1")
		(23 "Eco2.User" user "User.Eco2")
		(25 "Edge.Cuts" user "Board Geometry/Outline")
		(27 "Margin" user)
		(31 "F.CrtYd" user "Package Geometry/Place Bound Top")
		(29 "B.CrtYd" user "Package Geometry/Place Bound Bottom")
		(35 "F.Fab" user "Ref Des/Assembly Top")
		(33 "B.Fab" user "Ref Des/Assembly Bottom")
	)
	(footprint ""
		(layer "F.Cu")
		(at 206.12608 -258.091686)
		(property "Reference" "J32"
			(at 0.68834 -81.826608 0)
			(unlocked yes)
			(layer "F.SilkS")
			(effects
				(font
					(size 0.7874 0.5842)
					(thickness 0.1524)
				)
				(justify left)
			)
		)
		(property "Value" ""
			(at 0 0 0)
			(layer "F.Fab")
			(effects
				(font
					(size 1.27 1.27)
				)
			)
		)
		(duplicate_pad_numbers_are_jumpers no)
		(pad "225" smd rect
			(at 2.050034 9.774936 270)
			(size 0.519938 1.4986)
			(layers "F.Cu" "F.Mask" "F.Paste")
			(net "M_H_CPU1_SB_CA<5>")
		)
		(pad "226" smd rect
			(at 2.050034 10.625074 270)
			(size 0.519938 1.4986)
			(layers "F.Cu" "F.Mask" "F.Paste")
			(net "GND")
		)
		(pad "227" smd rect
			(at 2.050034 11.474958 270)
			(size 0.519938 1.4986)
			(layers "F.Cu" "F.Mask" "F.Paste")
			(net "M_H_CPU1_SB_PAR")
		)
		(pad "228" smd rect
			(at 2.050034 12.325096 270)
			(size 0.519938 1.4986)
			(layers "F.Cu" "F.Mask" "F.Paste")
			(net "GND")
		)
		(pad "229" smd rect
			(at 2.050034 13.17498 270)
			(size 0.519938 1.4986)
			(layers "F.Cu" "F.Mask" "F.Paste")
			(net "M_H_CPU1_SB_CS_N<3>")
		)
		(pad "230" smd rect
			(at 2.050034 14.025118 270)
			(size 0.519938 1.4986)
			(layers "F.Cu" "F.Mask" "F.Paste")
			(net "GND")
		)
		(pad "231" smd rect
			(at 2.050034 14.875002 270)
			(size 0.519938 1.4986)
			(layers "F.Cu" "F.Mask" "F.Paste")
			(net "TP_CHH_CPU1_DIMM2_FRU_5")
		)
		(pad "232" smd rect
			(at 2.050034 15.724886 270)
			(size 0.519938 1.4986)
			(layers "F.Cu" "F.Mask" "F.Paste")
			(net "TP_CHH_CPU1_DIMM2_FRU_6")
		)
		(pad "233" smd rect
			(at 2.050034 16.575024 270)
			(size 0.519938 1.4986)
			(layers "F.Cu" "F.Mask" "F.Paste")
			(net "GND")
		)
		(pad "234" smd rect
			(at 2.050034 17.424908 270)
			(size 0.519938 1.4986)
			(layers "F.Cu" "F.Mask" "F.Paste")
			(net "M_H_CPU1_SB_CB<6>")
		)
		(pad "235" smd rect
			(at 2.050034 18.275046 270)
			(size 0.519938 1.4986)
			(layers "F.Cu" "F.Mask" "F.Paste")
			(net "GND")
		)
		(pad "236" smd rect
			(at 2.050034 19.12493 270)
			(size 0.519938 1.4986)
			(layers "F.Cu" "F.Mask" "F.Paste")
			(net "M_H_CPU1_SB_CB<7>")
		)
		(pad "237" smd rect
			(at 2.050034 19.975068 270)
			(size 0.519938 1.4986)
			(layers "F.Cu" "F.Mask" "F.Paste")
			(net "GND")
		)
		(pad "238" smd rect
			(at 2.050034 20.824952 270)
			(size 0.519938 1.4986)
			(layers "F.Cu" "F.Mask" "F.Paste")
			(net "M_H_CPU1_SB_DQS_DN<4>")
		)
		(pad "239" smd rect
			(at 2.050034 21.67509 270)
			(size 0.519938 1.4986)
			(layers "F.Cu" "F.Mask" "F.Paste")
			(net "M_H_CPU1_SB_DQS_DP<4>")
		)
		(pad "240" smd rect
			(at 2.050034 22.524974 270)
			(size 0.519938 1.4986)
			(layers "F.Cu" "F.Mask" "F.Paste")
			(net "GND")
		)
		(pad "241" smd rect
			(at 2.050034 23.375112 270)
			(size 0.519938 1.4986)
			(layers "F.Cu" "F.Mask" "F.Paste")
			(net "M_H_CPU1_SB_CB<2>")
		)
		(pad "242" smd rect
			(at 2.050034 24.224996 270)
			(size 0.519938 1.4986)
			(layers "F.Cu" "F.Mask" "F.Paste")
			(net "GND")
		)
		(pad "243" smd rect
			(at 2.050034 25.07488 270)
			(size 0.519938 1.4986)
			(layers "F.Cu" "F.Mask" "F.Paste")
			(net "M_H_CPU1_SB_CB<3>")
		)
		(pad "244" smd rect
			(at 2.050034 25.925018 270)
			(size 0.519938 1.4986)
			(layers "F.Cu" "F.Mask" "F.Paste")
			(net "GND")
		)
		(pad "245" smd rect
			(at 2.050034 26.774902 270)
			(size 0.519938 1.4986)
			(layers "F.Cu" "F.Mask" "F.Paste")
			(net "M_H_CPU1_SB_DQ<2>")
		)
		(pad "246" smd rect
			(at 2.050034 27.62504 270)
			(size 0.519938 1.4986)
			(layers "F.Cu" "F.Mask" "F.Paste")
			(net "GND")
		)
		(pad "247" smd rect
			(at 2.050034 28.474924 270)
			(size 0.519938 1.4986)
			(layers "F.Cu" "F.Mask" "F.Paste")
			(net "M_H_CPU1_SB_DQ<3>")
		)
		(pad "248" smd rect
			(at 2.050034 29.325062 270)
			(size 0.519938 1.4986)
			(layers "F.Cu" "F.Mask" "F.Paste")
			(net "GND")
		)
		(pad "249" smd rect
			(at 2.050034 30.174946 270)
			(size 0.519938 1.4986)
			(layers "F.Cu" "F.Mask" "F.Paste")
			(net "M_H_CPU1_SB_DQS_DN<5>")
		)
		(pad "250" smd rect
			(at 2.050034 31.025084 270)
			(size 0.519938 1.4986)
			(layers "F.Cu" "F.Mask" "F.Paste")
			(net "M_H_CPU1_SB_DQS_DP<5>")
		)
		(pad "251" smd rect
			(at 2.050034 31.874968 270)
			(size 0.519938 1.4986)
			(layers "F.Cu" "F.Mask" "F.Paste")
			(net "GND")
		)
		(pad "252" smd rect
			(at 2.050034 32.725106 270)
			(size 0.519938 1.4986)
			(layers "F.Cu" "F.Mask" "F.Paste")
			(net "M_H_CPU1_SB_DQ<6>")
		)
		(pad "253" smd rect
			(at 2.050034 33.57499 270)
			(size 0.519938 1.4986)
			(layers "F.Cu" "F.Mask" "F.Paste")
			(net "GND")
		)
		(pad "254" smd rect
			(at 2.050034 34.425128 270)
			(size 0.519938 1.4986)
			(layers "F.Cu" "F.Mask" "F.Paste")
			(net "M_H_CPU1_SB_DQ<7>")
		)
		(pad "255" smd rect
			(at 2.050034 35.275012 270)
			(size 0.519938 1.4986)
			(layers "F.Cu" "F.Mask" "F.Paste")
			(net "GND")
		)
		(pad "256" smd rect
			(at 2.050034 36.124896 270)
			(size 0.519938 1.4986)
			(layers "F.Cu" "F.Mask" "F.Paste")
			(net "M_H_CPU1_SB_DQ<10>")
		)
		(pad "257" smd rect
			(at 2.050034 36.975034 270)
			(size 0.519938 1.4986)
			(layers "F.Cu" "F.Mask" "F.Paste")
			(net "GND")
		)
		(pad "258" smd rect
			(at 2.050034 37.824918 270)
			(size 0.519938 1.4986)
			(layers "F.Cu" "F.Mask" "F.Paste")
			(net "M_H_CPU1_SB_DQ<11>")
		)
		(pad "259" smd rect
			(at 2.050034 38.675056 270)
			(size 0.519938 1.4986)
			(layers "F.Cu" "F.Mask" "F.Paste")
			(net "GND")
		)
		(pad "260" smd rect
			(at 2.050034 39.52494 270)
			(size 0.519938 1.4986)
			(layers "F.Cu" "F.Mask" "F.Paste")
			(net "M_H_CPU1_SB_DQS_DN<6>")
		)
		(pad "261" smd rect
			(at 2.050034 40.375078 270)
			(size 0.519938 1.4986)
			(layers "F.Cu" "F.Mask" "F.Paste")
			(net "M_H_CPU1_SB_DQS_DP<6>")
		)
		(pad "262" smd rect
			(at 2.050034 41.224962 270)
			(size 0.519938 1.4986)
			(layers "F.Cu" "F.Mask" "F.Paste")
			(net "GND")
		)
		(pad "263" smd rect
			(at 2.050034 42.0751 270)
			(size 0.519938 1.4986)
			(layers "F.Cu" "F.Mask" "F.Paste")
			(net "M_H_CPU1_SB_DQ<14>")
		)
		(pad "264" smd rect
			(at 2.050034 42.924984 270)
			(size 0.519938 1.4986)
			(layers "F.Cu" "F.Mask" "F.Paste")
			(net "GND")
		)
		(pad "265" smd rect
			(at 2.050034 43.775122 270)
			(size 0.519938 1.4986)
			(layers "F.Cu" "F.Mask" "F.Paste")
			(net "M_H_CPU1_SB_DQ<15>")
		)
		(pad "266" smd rect
			(at 2.050034 44.625006 270)
			(size 0.519938 1.4986)
			(layers "F.Cu" "F.Mask" "F.Paste")
			(net "GND")
		)
		(pad "267" smd rect
			(at 2.050034 45.47489 270)
			(size 0.519938 1.4986)
			(layers "F.Cu" "F.Mask" "F.Paste")
			(net "M_H_CPU1_SB_DQ<18>")
		)
		(pad "268" smd rect
			(at 2.050034 46.325028 270)
			(size 0.519938 1.4986)
			(layers "F.Cu" "F.Mask" "F.Paste")
			(net "GND")
		)
		(pad "269" smd rect
			(at 2.050034 47.174912 270)
			(size 0.519938 1.4986)
			(layers "F.Cu" "F.Mask" "F.Paste")
			(net "M_H_CPU1_SB_DQ<19>")
		)
		(pad "270" smd rect
			(at 2.050034 48.02505 270)
			(size 0.519938 1.4986)
			(layers "F.Cu" "F.Mask" "F.Paste")
			(net "GND")
		)
		(pad "271" smd rect
			(at 2.050034 48.874934 270)
			(size 0.519938 1.4986)
			(layers "F.Cu" "F.Mask" "F.Paste")
			(net "M_H_CPU1_SB_DQS_DN<7>")
		)
		(pad "272" smd rect
			(at 2.050034 49.725072 270)
			(size 0.519938 1.4986)
			(layers "F.Cu" "F.Mask" "F.Paste")
			(net "M_H_CPU1_SB_DQS_DP<7>")
		)
		(pad "273" smd rect
			(at 2.050034 50.574956 270)
			(size 0.519938 1.4986)
			(layers "F.Cu" "F.Mask" "F.Paste")
			(net "GND")
		)
		(pad "274" smd rect
			(at 2.050034 51.425094 270)
			(size 0.519938 1.4986)
			(layers "F.Cu" "F.Mask" "F.Paste")
			(net "M_H_CPU1_SB_DQ<22>")
		)
		(pad "275" smd rect
			(at 2.050034 52.274978 270)
			(size 0.519938 1.4986)
			(layers "F.Cu" "F.Mask" "F.Paste")
			(net "GND")
		)
		(pad "276" smd rect
			(at 2.050034 53.125116 270)
			(size 0.519938 1.4986)
			(layers "F.Cu" "F.Mask" "F.Paste")
			(net "M_H_CPU1_SB_DQ<23>")
		)
		(pad "277" smd rect
			(at 2.050034 53.975 270)
			(size 0.519938 1.4986)
			(layers "F.Cu" "F.Mask" "F.Paste")
			(net "GND")
		)
		(pad "278" smd rect
			(at 2.050034 54.824884 270)
			(size 0.519938 1.4986)
			(layers "F.Cu" "F.Mask" "F.Paste")
			(net "M_H_CPU1_SB_DQ<26>")
		)
		(pad "279" smd rect
			(at 2.050034 55.675022 270)
			(size 0.519938 1.4986)
			(layers "F.Cu" "F.Mask" "F.Paste")
			(net "GND")
		)
		(pad "280" smd rect
			(at 2.050034 56.524906 270)
			(size 0.519938 1.4986)
			(layers "F.Cu" "F.Mask" "F.Paste")
			(net "M_H_CPU1_SB_DQ<27>")
		)
		(pad "281" smd rect
			(at 2.050034 57.375044 270)
			(size 0.519938 1.4986)
			(layers "F.Cu" "F.Mask" "F.Paste")
			(net "GND")
		)
		(pad "282" smd rect
			(at 2.050034 58.224928 270)
			(size 0.519938 1.4986)
			(layers "F.Cu" "F.Mask" "F.Paste")
			(net "M_H_CPU1_SB_DQS_DN<8>")
		)
		(pad "283" smd rect
			(at 2.050034 59.075066 270)
			(size 0.519938 1.4986)
			(layers "F.Cu" "F.Mask" "F.Paste")
			(net "M_H_CPU1_SB_DQS_DP<8>")
		)
		(pad "284" smd rect
			(at 2.050034 59.92495 270)
			(size 0.519938 1.4986)
			(layers "F.Cu" "F.Mask" "F.Paste")
			(net "GND")
		)
		(pad "285" smd rect
			(at 2.050034 60.775088 270)
			(size 0.519938 1.4986)
			(layers "F.Cu" "F.Mask" "F.Paste")
			(net "M_H_CPU1_SB_DQ<30>")
		)
		(pad "286" smd rect
			(at 2.050034 61.624972 270)
			(size 0.519938 1.4986)
			(layers "F.Cu" "F.Mask" "F.Paste")
			(net "GND")
		)
		(pad "287" smd rect
			(at 2.050034 62.47511 270)
			(size 0.519938 1.4986)
			(layers "F.Cu" "F.Mask" "F.Paste")
			(net "M_H_CPU1_SB_DQ<31>")
		)
		(pad "288" smd rect
			(at 2.050034 63.324994 270)
			(size 0.519938 1.4986)
			(layers "F.Cu" "F.Mask" "F.Paste")
			(net "GND")
		)
		(pad "G1" thru_hole oval
			(at 0 -68.97497)
			(size 2.8194 1.5748)
			(drill oval 2.4384 1.1938)
			(layers "*.Cu" "*.Mask")
			(remove_unused_layers no)
			(net "GND")
			(clearance 0.127)
			(thermal_gap 0.127)
		)
		(pad "G2" thru_hole oval
			(at 0 3.875024)
			(size 2.8194 1.5748)
			(drill oval 2.4384 1.1938)
			(layers "*.Cu" "*.Mask")
			(remove_unused_layers no)
			(net "GND")
			(clearance 0.127)
			(thermal_gap 0.127)
		)
		(pad "G3" thru_hole oval
			(at 0 68.97497)
			(size 2.8194 1.5748)
			(drill oval 2.4384 1.1938)
			(layers "*.Cu" "*.Mask")
			(remove_unused_layers no)
			(net "GND")
			(clearance 0.127)
			(thermal_gap 0.127)
		)
	)
)
